# S9S_MB_2U (Grand Teton) — schematic netlist excerpt (pin names and nets, part order shuffled) for the footprints in the layout excerpt that follows; sources: Cadence DE-HDL packaged netlist, KiCad conversion of 03242023_DA0F0TMBIJ0_F0T_Motherboard_J_brd_V01_OCP.brd

PC274_P0_4  Q_CAP  3300PF 50V 10% X7R  pkg 0402  page 268 : A = SW_P12V_PVCCIN_CPU0_FLT ; B = GND
R1755  Q_RES  33.2 1% CHIP  pkg 0402LF  page 222 : A = SGPIO_DO_1 ; B = SGPIO_BMC_DOUT

(kicad_pcb
	(version 20260206)
	(generator "pcbnew")
	(generator_version "10.0")
	(general
		(thickness 1.6)
		(legacy_teardrops no)
	)
	(paper "A4")
	(title_block
		(title "03242023_DA0F0TMBIJ0_F0T_Motherboard_J_brd_V01_OCP.brd")
		(comment 1 "Grand Teton / footprints 1590-1591 of 6105")
	)
	(layers
		(0 "F.Cu" signal "TOP")
		(4 "In1.Cu" signal "GND")
		(6 "In2.Cu" signal "IN1")
		(8 "In3.Cu" signal "GND1")
		(10 "In4.Cu" signal "IN2")
		(12 "In5.Cu" signal "GND2")
		(14 "In6.Cu" signal "IN3")
		(16 "In7.Cu" signal "GND3")
		(18 "In8.Cu" signal "VCC")
		(20 "In9.Cu" signal "VCC1")
		(22 "In10.Cu" signal "GND4")
		(24 "In11.Cu" signal "IN4")
		(26 "In12.Cu" signal "GND5")
		(28 "In13.Cu" signal "IN5")
		(30 "In14.Cu" signal "GND6")
		(32 "In15.Cu" signal "IN6")
		(34 "In16.Cu" signal "GND7")
		(2 "B.Cu" signal "BOTTOM")
		(9 "F.Adhes" user "F.Adhesive")
		(11 "B.Adhes" user "B.Adhesive")
		(13 "F.Paste" user "Package Geometry/Pastemask Top")
		(15 "B.Paste" user "Package Geometry/Pastemask Bottom")
		(5 "F.SilkS" user "Ref Des/Silkscreen Top")
		(7 "B.SilkS" user "Ref Des/Silkscreen Bottom")
		(1 "F.Mask" user "Board Geometry/Soldermask Top")
		(3 "B.Mask" user "Board Geometry/Soldermask Bottom")
		(17 "Dwgs.User" user "User.Drawings")
		(19 "Cmts.User" user "User.Comments")
		(21 "Eco1.User" user "User.Eco1")
		(23 "Eco2.User" user "User.Eco2")
		(25 "Edge.Cuts" user "Board Geometry/Outline")
		(27 "Margin" user)
		(31 "F.CrtYd" user "Package Geometry/Place Bound Top")
		(29 "B.CrtYd" user "Package Geometry/Place Bound Bottom")
		(35 "F.Fab" user "Ref Des/Assembly Top")
		(33 "B.Fab" user "Ref Des/Assembly Bottom")
	)
	(footprint ""
		(layer "F.Cu")
		(at 373.476774 -335.176368)
		(property "Reference" "PC274_P0_4"
			(at 0 0 0)
			(layer "F.SilkS")
			(hide yes)
			(effects
				(font
					(size 1.27 1.27)
				)
			)
		)
		(property "Value" ""
			(at 0 0 0)
			(layer "F.Fab")
			(effects
				(font
					(size 1.27 1.27)
				)
			)
		)
		(duplicate_pad_numbers_are_jumpers no)
		(fp_line
			(start -0.7874 -0.4064)
			(end 0.7874 -0.4064)
			(stroke
				(width 0.1524)
				(type default)
			)
			(layer "F.SilkS")
		)
		(fp_line
			(start -0.7874 0.4064)
			(end -0.7874 -0.4064)
			(stroke
				(width 0.1524)
				(type default)
			)
			(layer "F.SilkS")
		)
		(fp_line
			(start 0.7874 -0.4064)
			(end 0.7874 0.4064)
			(stroke
				(width 0.1524)
				(type default)
			)
			(layer "F.SilkS")
		)
		(fp_line
			(start 0.7874 0.4064)
			(end -0.7874 0.4064)
			(stroke
				(width 0.1524)
				(type default)
			)
			(layer "F.SilkS")
		)
		(fp_line
			(start -0.67945 -0.305054)
			(end -0.12065 -0.305054)
			(stroke
				(width 0.1)
				(type default)
			)
			(layer "F.Fab")
		)
		(fp_line
			(start -0.67945 0.3048)
			(end -0.67945 -0.305054)
			(stroke
				(width 0.1)
				(type default)
			)
			(layer "F.Fab")
		)
		(fp_line
			(start -0.12065 -0.305054)
			(end -0.12065 -0.2794)
			(stroke
				(width 0.1)
				(type default)
			)
			(layer "F.Fab")
		)
		(fp_line
			(start -0.12065 -0.2794)
			(end 0.12065 -0.2794)
			(stroke
				(width 0.1)
				(type default)
			)
			(layer "F.Fab")
		)
		(fp_line
			(start -0.12065 0.2794)
			(end -0.12065 0.3048)
			(stroke
				(width 0.1)
				(type default)
			)
			(layer "F.Fab")
		)
		(fp_line
			(start -0.12065 0.3048)
			(end -0.67945 0.3048)
			(stroke
				(width 0.1)
				(type default)
			)
			(layer "F.Fab")
		)
		(fp_line
			(start 0.120396 0.2794)
			(end -0.12065 0.2794)
			(stroke
				(width 0.1)
				(type default)
			)
			(layer "F.Fab")
		)
		(fp_line
			(start 0.120396 0.3048)
			(end 0.120396 0.2794)
			(stroke
				(width 0.1)
				(type default)
			)
			(layer "F.Fab")
		)
		(fp_line
			(start 0.12065 -0.3048)
			(end 0.67945 -0.3048)
			(stroke
				(width 0.1)
				(type default)
			)
			(layer "F.Fab")
		)
		(fp_line
			(start 0.12065 -0.2794)
			(end 0.12065 -0.3048)
			(stroke
				(width 0.1)
				(type default)
			)
			(layer "F.Fab")
		)
		(fp_line
			(start 0.67945 -0.3048)
			(end 0.67945 0.3048)
			(stroke
				(width 0.1)
				(type default)
			)
			(layer "F.Fab")
		)
		(fp_line
			(start 0.67945 0.3048)
			(end 0.120396 0.3048)
			(stroke
				(width 0.1)
				(type default)
			)
			(layer "F.Fab")
		)
		(pad "1" smd circle
			(at -0.40005 0)
			(size 0 0)
			(layers "F.Cu" "F.Mask" "F.Paste")
			(net "SW_P12V_PVCCIN_CPU0_FLT")
		)
		(pad "2" smd circle
			(at 0.40005 0)
			(size 0 0)
			(layers "F.Cu" "F.Mask" "F.Paste")
			(net "GND")
		)
	)
	(footprint ""
		(layer "F.Cu")
		(at 164.592 -103.342948)
		(property "Reference" "R1755"
			(at 0 0 0)
			(layer "F.SilkS")
			(hide yes)
			(effects
				(font
					(size 1.27 1.27)
				)
			)
		)
		(property "Value" ""
			(at 0 0 0)
			(layer "F.Fab")
			(effects
				(font
					(size 1.27 1.27)
				)
			)
		)
		(duplicate_pad_numbers_are_jumpers no)
		(fp_line
			(start -0.7874 -0.4064)
			(end 0.7874 -0.4064)
			(stroke
				(width 0.1524)
				(type default)
			)
			(layer "F.SilkS")
		)
		(fp_line
			(start -0.7874 0.4064)
			(end -0.7874 -0.4064)
			(stroke
				(width 0.1524)
				(type default)
			)
			(layer "F.SilkS")
		)
		(fp_line
			(start 0.7874 -0.4064)
			(end 0.7874 0.4064)
			(stroke
				(width 0.1524)
				(type default)
			)
			(layer "F.SilkS")
		)
		(fp_line
			(start 0.7874 0.4064)
			(end -0.7874 0.4064)
			(stroke
				(width 0.1524)
				(type default)
			)
			(layer "F.SilkS")
		)
		(fp_line
			(start -0.67945 -0.305054)
			(end -0.12065 -0.305054)
			(stroke
				(width 0.1)
				(type default)
			)
			(layer "F.Fab")
		)
		(fp_line
			(start -0.67945 0.3048)
			(end -0.67945 -0.305054)
			(stroke
				(width 0.1)
				(type default)
			)
			(layer "F.Fab")
		)
		(fp_line
			(start -0.12065 -0.305054)
			(end -0.12065 -0.2794)
			(stroke
				(width 0.1)
				(type default)
			)
			(layer "F.Fab")
		)
		(fp_line
			(start -0.12065 -0.2794)
			(end 0.12065 -0.2794)
			(stroke
				(width 0.1)
				(type default)
			)
			(layer "F.Fab")
		)
		(fp_line
			(start -0.12065 0.2794)
			(end -0.12065 0.3048)
			(stroke
				(width 0.1)
				(type default)
			)
			(layer "F.Fab")
		)
		(fp_line
			(start -0.12065 0.3048)
			(end -0.67945 0.3048)
			(stroke
				(width 0.1)
				(type default)
			)
			(layer "F.Fab")
		)
		(fp_line
			(start 0.120396 0.2794)
			(end -0.12065 0.2794)
			(stroke
				(width 0.1)
				(type default)
			)
			(layer "F.Fab")
		)
		(fp_line
			(start 0.120396 0.3048)
			(end 0.120396 0.2794)
			(stroke
				(width 0.1)
				(type default)
			)
			(layer "F.Fab")
		)
		(fp_line
			(start 0.12065 -0.3048)
			(end 0.67945 -0.3048)
			(stroke
				(width 0.1)
				(type default)
			)
			(layer "F.Fab")
		)
		(fp_line
			(start 0.12065 -0.2794)
			(end 0.12065 -0.3048)
			(stroke
				(width 0.1)
				(type default)
			)
			(layer "F.Fab")
		)
		(fp_line
			(start 0.67945 -0.3048)
			(end 0.67945 0.3048)
			(stroke
				(width 0.1)
				(type default)
			)
			(layer "F.Fab")
		)
		(fp_line
			(start 0.67945 0.3048)
			(end 0.120396 0.3048)
			(stroke
				(width 0.1)
				(type default)
			)
			(layer "F.Fab")
		)
		(pad "1" smd circle
			(at -0.40005 0)
			(size 0 0)
			(layers "F.Cu" "F.Mask" "F.Paste")
			(net "SGPIO_DO_1")
		)
		(pad "2" smd circle
			(at 0.40005 0)
			(size 0 0)
			(layers "F.Cu" "F.Mask" "F.Paste")
			(net "SGPIO_BMC_DOUT")
		)
	)
)
